# BASEBOARD_FAB2 (Tioga Pass) — schematic netlist excerpt (pin names and nets, part order shuffled) for the footprints in the layout excerpt that follows; sources: Cadence DE-HDL packaged netlist, KiCad conversion of Wiwynn_Tioga_Pass_MB.brd

C5G88  CAP_A  22.0UF 4V 20% X6S  pkg 0603V  page 243 : A = PVDDQ_GHJ ; B = GND
C2M7  CAP_A  1.0UF 6.3V 10% X6S  pkg 0402V  page 127 : A = P1V05_PCH_STBY_WM20_PLL ; B = GND
R4L2  RES  100.0 1% EMPTY  pkg 0402  page 220 : A = VSENSE_PVDDQ_DEF_P ; B = VSENSE_PVDDQ_DEF_N

(kicad_pcb
	(version 20260206)
	(generator "pcbnew")
	(generator_version "10.0")
	(general
		(thickness 1.6)
		(legacy_teardrops no)
	)
	(paper "A4")
	(title_block
		(title "Wiwynn_Tioga_Pass_MB.brd")
		(comment 1 "Tioga Pass / footprints 3228-3230 of 4770")
	)
	(layers
		(0 "F.Cu" signal "TOP")
		(4 "In1.Cu" signal "L2GND")
		(6 "In2.Cu" signal "L3")
		(8 "In3.Cu" signal "L4GND")
		(10 "In4.Cu" signal "L5")
		(12 "In5.Cu" signal "L6GND")
		(14 "In6.Cu" signal "L7VCC")
		(16 "In7.Cu" signal "L8VCC")
		(18 "In8.Cu" signal "L9GND")
		(20 "In9.Cu" signal "L10")
		(22 "In10.Cu" signal "L11GND")
		(24 "In11.Cu" signal "L12")
		(26 "In12.Cu" signal "L13GND")
		(2 "B.Cu" signal "BOTTOM")
		(9 "F.Adhes" user "F.Adhesive")
		(11 "B.Adhes" user "B.Adhesive")
		(13 "F.Paste" user "Package Geometry/Pastemask Top")
		(15 "B.Paste" user "Package Geometry/Pastemask Bottom")
		(5 "F.SilkS" user "Ref Des/Silkscreen Top")
		(7 "B.SilkS" user "Ref Des/Silkscreen Bottom")
		(1 "F.Mask" user "Board Geometry/Soldermask Top")
		(3 "B.Mask" user "Board Geometry/Soldermask Bottom")
		(17 "Dwgs.User" user "User.Drawings")
		(19 "Cmts.User" user "User.Comments")
		(21 "Eco1.User" user "User.Eco1")
		(23 "Eco2.User" user "User.Eco2")
		(25 "Edge.Cuts" user "Board Geometry/Outline")
		(27 "Margin" user)
		(31 "F.CrtYd" user "Package Geometry/Place Bound Top")
		(29 "B.CrtYd" user "Package Geometry/Place Bound Bottom")
		(35 "F.Fab" user "Ref Des/Assembly Top")
		(33 "B.Fab" user "Ref Des/Assembly Bottom")
	)
	(footprint ""
		(layer "B.Cu")
		(at 265.8872 -124.6886 -90)
		(property "Reference" "R4L2"
			(at 0 0 90)
			(layer "B.SilkS")
			(hide yes)
			(effects
				(font
					(size 1.27 1.27)
				)
				(justify mirror)
			)
		)
		(property "Value" ""
			(at 0 0 90)
			(layer "B.Fab")
			(effects
				(font
					(size 1.27 1.27)
				)
				(justify mirror)
			)
		)
		(duplicate_pad_numbers_are_jumpers no)
		(fp_rect
			(start 0.2794 -0.1016)
			(end -0.2794 0.9906)
			(stroke
				(width 0)
				(type default)
			)
			(fill no)
			(layer "B.CrtYd")
		)
		(fp_line
			(start -0.2794 0.9906)
			(end -0.2794 -0.1016)
			(stroke
				(width 0.1)
				(type default)
			)
			(layer "B.Fab")
		)
		(fp_line
			(start 0.2794 0.9906)
			(end -0.2794 0.9906)
			(stroke
				(width 0.1)
				(type default)
			)
			(layer "B.Fab")
		)
		(fp_line
			(start -0.2794 -0.1016)
			(end 0.2794 -0.1016)
			(stroke
				(width 0.1)
				(type default)
			)
			(layer "B.Fab")
		)
		(fp_line
			(start 0.2794 -0.1016)
			(end 0.2794 0.9906)
			(stroke
				(width 0.1)
				(type default)
			)
			(layer "B.Fab")
		)
		(pad "1" smd rect
			(at 0 0 90)
			(size 0.508 0.508)
			(layers "B.Cu" "B.Mask" "B.Paste")
			(net "VSENSE_PVDDQ_DEF_P")
		)
		(pad "2" smd rect
			(at 0 0.889 90)
			(size 0.508 0.508)
			(layers "B.Cu" "B.Mask" "B.Paste")
			(net "VSENSE_PVDDQ_DEF_N")
		)
		(zone
			(layer "B.Cu")
			(hatch none 0.5)
			(connect_pads
				(clearance 0)
			)
			(min_thickness 0.25)
			(keepout
				(tracks allowed)
				(vias not_allowed)
				(pads allowed)
				(copperpour not_allowed)
				(footprints allowed)
			)
			(placement
				(enabled no)
				(sheetname "")
			)
			(fill
				(thermal_gap 0.5)
				(thermal_bridge_width 0.5)
				(island_removal_mode 0)
			)
			(polygon
				(pts
					(xy 265.6332 -124.4346) (xy 265.6332 -124.9426) (xy 265.2522 -124.9426) (xy 265.2522 -124.4346)
				)
			)
		)
	)
	(footprint ""
		(layer "B.Cu")
		(at 403.4282 -122.936 180)
		(property "Reference" "C2M7"
			(at 0 0 0)
			(layer "B.SilkS")
			(hide yes)
			(effects
				(font
					(size 1.27 1.27)
				)
				(justify mirror)
			)
		)
		(property "Value" ""
			(at 0 0 0)
			(layer "B.Fab")
			(effects
				(font
					(size 1.27 1.27)
				)
				(justify mirror)
			)
		)
		(duplicate_pad_numbers_are_jumpers no)
		(fp_poly
			(pts
				(xy -0.3048 -0.1016) (xy -0.3048 0.9906) (xy 0.3048 0.9906) (xy 0.3048 -0.1016)
			)
			(stroke
				(width 0)
				(type default)
			)
			(fill no)
			(layer "B.CrtYd")
		)
		(fp_line
			(start 0.3048 0.9906)
			(end -0.3048 0.9906)
			(stroke
				(width 0.1)
				(type default)
			)
			(layer "B.Fab")
		)
		(fp_line
			(start 0.3048 -0.1016)
			(end 0.3048 0.9906)
			(stroke
				(width 0.1)
				(type default)
			)
			(layer "B.Fab")
		)
		(fp_line
			(start -0.3048 0.9906)
			(end -0.3048 -0.1016)
			(stroke
				(width 0.1)
				(type default)
			)
			(layer "B.Fab")
		)
		(fp_line
			(start -0.3048 -0.1016)
			(end 0.3048 -0.1016)
			(stroke
				(width 0.1)
				(type default)
			)
			(layer "B.Fab")
		)
		(pad "1" smd rect
			(at 0 0)
			(size 0.508 0.508)
			(layers "B.Cu" "B.Mask" "B.Paste")
			(net "P1V05_PCH_STBY_WM20_PLL")
		)
		(pad "2" smd rect
			(at 0 0.889)
			(size 0.508 0.508)
			(layers "B.Cu" "B.Mask" "B.Paste")
			(net "GND")
		)
		(zone
			(layer "B.Cu")
			(hatch none 0.5)
			(connect_pads
				(clearance 0)
			)
			(min_thickness 0.25)
			(keepout
				(tracks not_allowed)
				(vias allowed)
				(pads allowed)
				(copperpour not_allowed)
				(footprints allowed)
			)
			(placement
				(enabled no)
				(sheetname "")
			)
			(fill
				(thermal_gap 0.5)
				(thermal_bridge_width 0.5)
				(island_removal_mode 0)
			)
			(polygon
				(pts
					(xy 403.1742 -123.571) (xy 403.6822 -123.571) (xy 403.6822 -123.19) (xy 403.1742 -123.19)
				)
			)
		)
		(zone
			(layer "B.Cu")
			(hatch none 0.5)
			(connect_pads
				(clearance 0)
			)
			(min_thickness 0.25)
			(keepout
				(tracks allowed)
				(vias not_allowed)
				(pads allowed)
				(copperpour not_allowed)
				(footprints allowed)
			)
			(placement
				(enabled no)
				(sheetname "")
			)
			(fill
				(thermal_gap 0.5)
				(thermal_bridge_width 0.5)
				(island_removal_mode 0)
			)
			(polygon
				(pts
					(xy 403.1742 -123.19) (xy 403.6822 -123.19) (xy 403.6822 -123.571) (xy 403.1742 -123.571)
				)
			)
		)
	)
	(footprint ""
		(layer "B.Cu")
		(at 83.856068 -3.3528 -90)
		(property "Reference" "C5G88"
			(at -1.14681 0.76708 0)
			(unlocked yes)
			(layer "B.SilkS")
			(effects
				(font
					(size 0.7874 0.5842)
					(thickness 0.1524)
				)
				(justify mirror)
			)
		)
		(property "Value" ""
			(at 0 0 90)
			(layer "B.Fab")
			(effects
				(font
					(size 1.27 1.27)
				)
				(justify mirror)
			)
		)
		(duplicate_pad_numbers_are_jumpers no)
		(fp_rect
			(start 0.4953 1.6002)
			(end -0.4953 -0.2032)
			(stroke
				(width 0)
				(type default)
			)
			(fill no)
			(layer "B.CrtYd")
		)
		(fp_line
			(start -0.4953 1.6002)
			(end 0.4953 1.6002)
			(stroke
				(width 0.1)
				(type default)
			)
			(layer "B.Fab")
		)
		(fp_line
			(start 0.4953 1.6002)
			(end 0.4953 -0.2032)
			(stroke
				(width 0.1)
				(type default)
			)
			(layer "B.Fab")
		)
		(fp_line
			(start -0.4953 -0.2032)
			(end -0.4953 1.6002)
			(stroke
				(width 0.1)
				(type default)
			)
			(layer "B.Fab")
		)
		(fp_line
			(start 0.4953 -0.2032)
			(end -0.4953 -0.2032)
			(stroke
				(width 0.1)
				(type default)
			)
			(layer "B.Fab")
		)
		(pad "1" smd rect
			(at 0 0 90)
			(size 0.762 0.889)
			(layers "B.Cu" "B.Mask" "B.Paste")
			(net "PVDDQ_GHJ")
		)
		(pad "2" smd rect
			(at 0 1.397 90)
			(size 0.762 0.889)
			(layers "B.Cu" "B.Mask" "B.Paste")
			(net "GND")
		)
		(zone
			(layer "B.Cu")
			(hatch none 0.5)
			(connect_pads
				(clearance 0)
			)
			(min_thickness 0.25)
			(keepout
				(tracks not_allowed)
				(vias allowed)
				(pads allowed)
				(copperpour not_allowed)
				(footprints allowed)
			)
			(placement
				(enabled no)
				(sheetname "")
			)
			(fill
				(thermal_gap 0.5)
				(thermal_bridge_width 0.5)
				(island_removal_mode 0)
			)
			(polygon
				(pts
					(xy 82.903568 -2.9718) (xy 83.411568 -2.9718) (xy 83.411568 -3.7338) (xy 82.903568 -3.7338)
				)
			)
		)
	)
)
